#ISCELL
  cls sheet_a1 *
  *
#ISCELL
  cls gnd_sg *
  page524_i1
#CELL
  passive capacitor *
  page524_i10
#ISCELL
  cls gnd_sg *
  page524_i102
#CELL
  passive resistor *
  page524_i106
#CELL
  passive ferritebead *
  page524_i118
#ISCELL
  cls gnd_sg *
  page524_i119
#ISCELL
  cls gnd_sg *
  page524_i120
#CELL
  passive resistor *
  page524_i121
#CELL
  passive capacitor *
  page524_i123
#ISCELL
  cls gnd_sg *
  page524_i124
#CELL
  passive ferritebead *
  page524_i127
#CELL
  passive capacitor *
  page524_i128
#ISCELL
  cls offpage_out *
  page524_i135
#ISCELL
  cls offpage_out *
  page524_i136
#ISCELL
  cls offpage_out *
  page524_i137
#ISCELL
  cls offpage_in *
  page524_i138
#CELL
  passive resistor *
  page524_i139
#CELL
  passive resistor *
  page524_i140
#CELL
  passive resistor *
  page524_i141
#CELL
  passive resistor *
  page524_i142
#ISCELL
  cls offpage_out *
  page524_i146
#ISCELL
  cls offpage_in *
  page524_i147
#CELL
  passive resistor *
  page524_i149
#CELL
  passive resistor *
  page524_i150
#CELL
  passive resistor *
  page524_i153
#CELL
  passive resistor *
  page524_i154
#CELL
  passive resistor *
  page524_i166
#CELL
  passive resistor *
  page524_i169
#CELL
  passive resistor *
  page524_i170
#ISCELL
  cls offpage_bi *
  page524_i171
#ISCELL
  cls offpage_out *
  page524_i172
#CELL
  connector g200_10283_01 *
  page524_i173
#ISCELL
  cls offpage_in *
  page524_i176
#CELL
  passive resistor *
  page524_i184
#CELL
  passive resistor *
  page524_i187
#CELL
  passive resistor *
  page524_i188
#CELL
  passive resistor *
  page524_i190
#CELL
  passive resistor *
  page524_i191
#ISCELL
  cls offpage_in *
  page524_i195
#ISCELL
  cls offpage_out *
  page524_i196
#ISCELL
  cls offpage_out *
  page524_i197
#CELL
  passive resistor *
  page524_i198
#CELL
  memory cat93c46vi_gt3_soic8 *
  page524_i200
#CELL
  memory cat93c46vi_gt3_soic8 *
  page524_i201
#ISCELL
  cls gnd_sg *
  page524_i204
#CELL
  passive resistor *
  page524_i206
#CELL
  passive resistor *
  page524_i207
#CELL
  passive resistor *
  page524_i208
#CELL
  passive resistor *
  page524_i23
#ISCELL
  cls gnd_sg *
  page524_i25
#CELL
  passive resistor *
  page524_i26
#CELL
  passive resistor *
  page524_i27
#CELL
  passive resistor *
  page524_i28
#CELL
  passive resistor *
  page524_i287
#ISCELL
  cls gnd_sg *
  page524_i288
#ISCELL
  cls offpage_out *
  page524_i297
#ISCELL
  cls offpage_out *
  page524_i298
#ISCELL
  cls offpage_out *
  page524_i299
#CELL
  other cl1001485a *
  page524_i3
#CELL
  passive resistor *
  page524_i310
#CELL
  cls tp_piont *
  page524_i311
#CELL
  cls tp_piont *
  page524_i312
#CELL
  cls tp_piont *
  page524_i313
#CELL
  cls tp_piont *
  page524_i314
#CELL
  cls tp_piont *
  page524_i315
#CELL
  cls tp_piont *
  page524_i316
#ISCELL
  cls offpage_in *
  page524_i350
#ISCELL
  cls vcc *
  page524_i359
#ISCELL
  cls vcc *
  page524_i360
#ISCELL
  cls vcc *
  page524_i362
#ISCELL
  cls vcc *
  page524_i363
#ISCELL
  cls vcc *
  page524_i364
#ISCELL
  cls vcc *
  page524_i365
#CELL
  passive resistor *
  page524_i368
#ISCELL
  cls offpage_out *
  page524_i370
#CELL
  passive capacitor *
  page524_i373
#CELL
  passive capacitor *
  page524_i374
#CELL
  passive capacitor *
  page524_i375
#CELL
  passive capacitor *
  page524_i376
#CELL
  passive capacitor *
  page524_i377
#CELL
  passive capacitor *
  page524_i378
#CELL
  passive capacitor *
  page524_i379
#CELL
  passive capacitor *
  page524_i380
#ISCELL
  cls offpage_bi *
  page524_i384
#ISCELL
  cls offpage_bi *
  page524_i385
#ISCELL
  cls vcc *
  page524_i386
#ISCELL
  cls offpage_bi *
  page524_i389
#ISCELL
  cls offpage_bi *
  page524_i390
#ISCELL
  cls offpage_bi *
  page524_i391
#ISCELL
  cls offpage_bi *
  page524_i392
#ISCELL
  cls gnd_sg *
  page524_i393
#ISCELL
  cls vcc *
  page524_i394
#CELL
  passive resistor *
  page524_i395
#ISCELL
  cls offpage_out *
  page524_i399
#CELL
  stdlogic ts3a5018pwr_tssop16 *
  page524_i400
#ISCELL
  cls offpage_out *
  page524_i401
#ISCELL
  cls offpage_bi *
  page524_i402
#ISCELL
  cls offpage_bi *
  page524_i403
#ISCELL
  cls offpage_out *
  page524_i404
#ISCELL
  cls offpage_bi *
  page524_i405
#ISCELL
  cls offpage_bi *
  page524_i406
#CELL
  interface nlasb3157dft2g_sc88 *
  page524_i407
#CELL
  interface nlasb3157dft2g_sc88 *
  page524_i408
#ISCELL
  cls offpage_in *
  page524_i409
#ISCELL
  cls offpage_bi *
  page524_i410
#CELL
  passive resistor *
  page524_i411
#CELL
  passive resistor *
  page524_i412
#ISCELL
  cls offpage_bi *
  page524_i413
#ISCELL
  cls offpage_in *
  page524_i414
#ISCELL
  cls offpage_in *
  page524_i415
#ISCELL
  cls offpage_in *
  page524_i416
#ISCELL
  cls offpage_out *
  page524_i417
#ISCELL
  cls offpage_out *
  page524_i418
#ISCELL
  cls offpage_in *
  page524_i419
#ISCELL
  cls offpage_in *
  page524_i420
#ISCELL
  cls offpage_in *
  page524_i421
#ISCELL
  cls offpage_out *
  page524_i422
#CELL
  passive resistor *
  page524_i423
#CELL
  passive resistor *
  page524_i424
#CELL
  stdlogic ts3a5018pwr_tssop16 *
  page524_i425
#ISCELL
  cls offpage_in *
  page524_i426
#ISCELL
  cls offpage_in *
  page524_i427
#ISCELL
  cls offpage_out *
  page524_i428
#ISCELL
  cls offpage_in *
  page524_i429
#CELL
  passive resistor *
  page524_i430
#CELL
  passive resistor *
  page524_i431
#CELL
  passive resistor *
  page524_i432
#ISCELL
  cls offpage_bi *
  page524_i433
#ISCELL
  cls vcc *
  page524_i434
#ISCELL
  cls gnd_sg *
  page524_i435
#ISCELL
  cls offpage_bi *
  page524_i436
#ISCELL
  cls vcc *
  page524_i437
#ISCELL
  cls gnd_sg *
  page524_i438
#ISCELL
  cls offpage_bi *
  page524_i439
#ISCELL
  cls vcc *
  page524_i44
#CELL
  passive resistor *
  page524_i440
#CELL
  passive resistor *
  page524_i441
#CELL
  passive resistor *
  page524_i442
#CELL
  passive resistor *
  page524_i443
#ISCELL
  cls gnd_sg *
  page524_i444
#CELL
  discrete powermos_3p_nch_v1 *
  page524_i445
#CELL
  passive resistor *
  page524_i446
#ISCELL
  cls offpage_in *
  page524_i447
#CELL
  stdlogic ts3a5018pwr_tssop16 *
  page524_i448
#ISCELL
  cls offpage_bi *
  page524_i449
#ISCELL
  cls offpage_out *
  page524_i450
#ISCELL
  cls offpage_bi *
  page524_i451
#ISCELL
  cls offpage_out *
  page524_i452
#ISCELL
  cls offpage_bi *
  page524_i453
#ISCELL
  cls offpage_bi *
  page524_i454
#ISCELL
  cls offpage_in *
  page524_i455
#ISCELL
  cls offpage_in *
  page524_i456
#ISCELL
  cls offpage_bi *
  page524_i457
#ISCELL
  cls offpage_in *
  page524_i458
#CELL
  passive resistor *
  page524_i459
#CELL
  passive resistor *
  page524_i460
#ISCELL
  cls vcc *
  page524_i461
#CELL
  passive resistor *
  page524_i462
#CELL
  passive resistor *
  page524_i463
#CELL
  passive resistor *
  page524_i464
#ISCELL
  cls gnd_sg *
  page524_i465
#CELL
  passive resistor *
  page524_i466
#CELL
  passive resistor *
  page524_i467
#CELL
  passive resistor *
  page524_i468
#CELL
  passive resistor *
  page524_i469
#ISCELL
  cls vcc *
  page524_i470
#ISCELL
  cls offpage_in *
  page524_i471
#ISCELL
  cls offpage_in *
  page524_i472
#CELL
  stdlogic ts3a5018pwr_tssop16 *
  page524_i473
#CELL
  passive capacitor *
  page524_i474
#ISCELL
  cls gnd_sg *
  page524_i475
#CELL
  passive capacitor *
  page524_i476
#CELL
  stdlogic ts3a5018pwr_tssop16 *
  page524_i478
#ISCELL
  cls vcc *
  page524_i479
#ISCELL
  cls gnd_sg *
  page524_i480
#CELL
  stdlogic ts3a5018pwr_tssop16 *
  page524_i481
#CELL
  passive capacitor *
  page524_i482
#ISCELL
  cls gnd_sg *
  page524_i484
#CELL
  interface nlasb3157dft2g_sc88 *
  page524_i485
#CELL
  passive capacitor *
  page524_i486
#ISCELL
  cls vcc *
  page524_i487
#ISCELL
  cls gnd_sg *
  page524_i488
#ISCELL
  cls vcc *
  page524_i489
#CELL
  passive capacitor *
  page524_i490
#CELL
  interface nlasb3157dft2g_sc88 *
  page524_i491
#ISCELL
  cls gnd_sg *
  page524_i492
#CELL
  passive resistor *
  page524_i493
#CELL
  passive resistor *
  page524_i494
#CELL
  connector conn_usb_14p_gh4_f_ra_th *
  page524_i495
#ISCELL
  cls gnd_sg *
  page524_i496
#CELL
  passive resistor *
  page524_i497
#ISCELL
  cls gnd_sg *
  page524_i498
#ISCELL
  cls offpage_in *
  page524_i499
#ISCELL
  cls gnd_sg *
  page524_i5
#ISCELL
  cls offpage_in *
  page524_i501
#ISCELL
  cls offpage_in *
  page524_i502
#ISCELL
  cls gnd_sg *
  page524_i6
#CELL
  interface ft4232hl_reel_qfp64 *
  page524_i64
#CELL
  passive capacitor *
  page524_i7
#CELL
  clock xtal_4 *
  page524_i8
#ISCELL
  cls gnd_sg *
  page524_i9
#ISCELL
  cls gnd_sg *
  page524_i95
